FILE_TYPE = CONNECTIVITY;
{Allegro Design Entry HDL 16.6-p007 (v16-6-112F) 10/10/2012}
"PAGE_NUMBER" = 95;
0"NC";
1"GND\g";
2"GND\g";
3"P3V3\g";
4"P3V3_STBY\g";
5"GND\g";
6"GND\g";
7"GND\g";
8"GND\g";
9"GND\g";
10"GND\g";
11"GND\g";
12"GND\g";
13"P3V3\g";
14"GND\g";
15"GND\g";
16"P3V3\g";
17"GND\g";
18"GND\g";
19"P3V3_STBY\g";
20"FM_PWRBRK_N";
21"FM_SYS_THROTTLE_LVC3";
22"H_CPU1_PROCHOT_G_N";
23"H_CPU0_MEMABC_MEMHOT_G_N";
24"H_CPU0_MEMDEF_MEMHOT_G_N";
25"H_CPU1_MEMGHJ_MEMHOT_G_N";
26"H_CPU1_MEMKLM_MEMHOT_G_N";
27"H_CPU0_PROCHOT_G_N";
28"FM_THROTTLE_N";
29"FM_THROTTLE_R_N";
30"IRQ_PVCCIN_CPU1_VRHOT_LVC3_N";
31"FM_PVCCIN_CPU1_PWR_IN_ALERT_N";
32"IRQ_CPU1_PROCHOT_G_N";
33"FM_SYS_THROTTLE_LVC3";
34"IRQ_CPU1_VRHOT";
35"H_CPU1_PROCHOT_G_N";
36"IRQ_PVCCIN_CPU0_VRHOT_LVC3_N";
37"FM_PVCCIN_CPU0_PWR_IN_ALERT_N";
38"IRQ_CPU0_PROCHOT_G_N";
39"IRQ_CPU0_VRHOT";
40"H_CPU0_PROCHOT_G_N";
%"GND"
"1","(-3100,425)","0","mstr_symbols","I1";
;
HDL_POWER"GND"
BODY_TYPE"PLUMBING"
SIZE"1B"
CDS_LIB"mstr_symbols"
VOLTAGE"0";
"A\NAC"1;
%"FET_N"
"8","(2150,1350)","0","mstr_discrete","I104";
;
CDS_SEC"1"
ROOM"PROC_SIDEBAND"
CDS_LOCATION"Q7E4"
SEC"1"
SEC_TYPE"SOT23"
CDS_LIB"mstr_discrete"
PACK_TYPE"SOT23"
MATERIAL"FET"
VALUE"2N7002"
PART_NUMBER"C79254-001"
LOCATION"Q7E4";
"GATE"
$PN"1"29;
"DRN"
$PN"3"33;
"SRC"
$PN"2"2;
%"GND"
"1","(2150,950)","0","mstr_symbols","I105";
;
HDL_POWER"GND"
ROOM"PROCHOT_MEMHOT_ISO"
BODY_TYPE"PLUMBING"
SIZE"1B"
CDS_LIB"mstr_symbols"
VOLTAGE"0.0V";
"A\NAC"2;
%"RES"
"2","(2150,1800)","0","mstr_discrete","I106";
;
CDS_SEC"1"
ROOM"PROC_SIDEBAND"
CDS_LOCATION"R7E7"
SEC"1"
SEC_TYPE"0402"
CDS_LIB"mstr_discrete"
WATTAGE"1/16W"
MATERIAL"CHIP"
PACK_TYPE"0402"
TOLERANCE"1%"
VALUE"4.75K"
PART_NUMBER"G21796-072"
LOCATION"R7E7";
"A"
$PN"1"3;
"B"
$PN"2"33;
%"P3V3"
"1","(2150,2075)","0","mstr_symbols","I107";
;
HDL_POWER"P3V3"
ROOM"PROCHOT_MEMHOT_ISO"
BODY_TYPE"PLUMBING"
SIZE"1B"
CDS_LIB"mstr_symbols"
VOLTAGE"3.3V";
"G\NAC"3;
%"RES"
"1","(1325,1250)","0","mstr_discrete","I108";
;
CDS_SEC"1"
ROOM"PROC_SIDEBAND"
CDS_LOCATION"R7E9"
SEC"1"
BOM_COST"PROC_SIDEBAND"
CDS_LIB"mstr_discrete"
SEC_TYPE"0402"
WATTAGE"1/16W"
MATERIAL"CHIP"
PACK_TYPE"0402"
TOLERANCE"5%"
VALUE"0.0"
PART_NUMBER"G21497-005"
LOCATION"R7E9";
"B"
$PN"2"29;
"A"
$PN"1"28;
%"FET_N_DUAL"
"5","(2475,4325)","0","mstr_discrete","I111";
;
CDS_SEC"1"
ROOM"HOT_EVENTS"
CDS_LOCATION"Q7E5"
SEC"1"
BOM_COST"PROC_SIDEBAND"
CDS_LIB"mstr_discrete"
SEC_TYPE"SMLF"
PACK_TYPE"SMLF"
MATERIAL"FET"
VALUE"NTJD4001N"
PART_NUMBER"E40049-001"
LOCATION"Q7E5";
"GATE <SIZE -1..0>"
$PN"2"38;
"SOURCE <SIZE-1..0>"
$PN"1"14;
"DRAIN <SIZE -1..0>"
$PN"6"39;
%"FET_N_DUAL"
"5","(2550,2875)","0","mstr_discrete","I112";
;
CDS_SEC"1"
ROOM"HOT_EVENTS"
CDS_LOCATION"Q7E6"
SEC"1"
CDS_LIB"mstr_discrete"
BOM_COST"PROC_SIDEBAND"
SEC_TYPE"SMLF"
PACK_TYPE"SMLF"
MATERIAL"FET"
VALUE"NTJD4001N"
PART_NUMBER"E40049-001"
LOCATION"Q7E6";
"GATE <SIZE -1..0>"
$PN"2"32;
"SOURCE <SIZE-1..0>"
$PN"1"17;
"DRAIN <SIZE -1..0>"
$PN"6"34;
%"FET_N_DUAL"
"5","(-3100,1950)","0","mstr_discrete","I113";
;
CDS_SEC"2"
ROOM"PROC_SIDEBAND"
CDS_LOCATION"Q2U1"
SEC"2"
BOM_COST"PROC_SIDEBAND"
CDS_LIB"mstr_discrete"
SEC_TYPE"SMLF"
PACK_TYPE"SMLF"
MATERIAL"FET"
VALUE"NTJD4001N"
PART_NUMBER"E40049-001"
LOCATION"Q2U1";
"GATE <SIZE -1..0>"
$PN"5"21;
"SOURCE <SIZE-1..0>"
$PN"4"10;
"DRAIN <SIZE -1..0>"
$PN"3"24;
%"P3V3_STBY"
"1","(1125,3675)","0","mstr_symbols","I114";
;
HDL_POWER"P3V3_STBY"
BODY_TYPE"PLUMBING"
CDS_LIB"mstr_symbols"
SIZE"1B"
VOLTAGE"3.3V";
"G\NAC"4;
%"CAP_A"
"1","(1125,3450)","0","dev_discrete","I115";
;
SEC"1"
SEC_TYPE"0402V"
CDS_SEC"1"
CDS_LIB"dev_discrete"
BOM_COST"PROC_SIDEBAND"
CDS_LOCATION"C7E4"
ROOM"PROC_SIDEBAND"
MATERIAL"X7R"
VOLTAGE"16V"
PACK_TYPE"0402V"
TOLERANCE"10%"
VALUE"0.1UF"
PART_NUMBER"A36096-030"
LOCATION"C7E4";
"B"
$PN"2"5;
"A"
$PN"1"4;
%"GND"
"1","(1125,3200)","0","mstr_symbols","I116";
;
HDL_POWER"GND"
BODY_TYPE"PLUMBING"
CDS_LIB"mstr_symbols"
SIZE"1B"
VOLTAGE"0.0V";
"A\NAC"5;
%"TTL1G08"
"1","(1550,4225)","0","mstr_ttl","I117";
;
CDS_SEC"1"
ROOM"CAT_ERR"
CDS_LOCATION"U7E2"
SEC"1"
CDS_LIB"mstr_ttl"
BOM_COST"PROC_SIDEBAND"
SEC_TYPE"SOTLF"
MATERIAL"IC"
PACK_TYPE"SOTLF"
VALUE"NC7SZ08"
PART_NUMBER"D10321-001"
LOCATION"U7E2"
POWER_GROUP"VCC=P3V3_STBY;GND=GND;";
"Y <SIZE-1..0>"
$PN"4"38;
"B <SIZE-1..0>"
$PN"2"36;
"A <SIZE-1..0>"
$PN"1"37;
%"TTL1G08"
"1","(1575,2775)","0","mstr_ttl","I118";
;
CDS_SEC"1"
ROOM"CAT_ERR"
CDS_LOCATION"U7E3"
SEC"1"
SEC_TYPE"SOTLF"
CDS_LIB"mstr_ttl"
BOM_COST"PROC_SIDEBAND"
MATERIAL"IC"
PACK_TYPE"SOTLF"
VALUE"NC7SZ08"
PART_NUMBER"D10321-001"
LOCATION"U7E3"
POWER_GROUP"VCC=P3V3_STBY;GND=GND;";
"Y <SIZE-1..0>"
$PN"4"32;
"B <SIZE-1..0>"
$PN"2"30;
"A <SIZE-1..0>"
$PN"1"31;
%"FET_N"
"8","(-3100,4550)","0","mstr_discrete","I119";
;
CDS_SEC"1"
CDS_LOCATION"Q7E8"
ROOM"PROC_SIDEBAND"
SEC"1"
CDS_LIB"mstr_discrete"
SEC_TYPE"SOT23"
PACK_TYPE"SOT23"
PART_NUMBER"C79254-001"
MATERIAL"FET"
VALUE"2N7002"
LOCATION"Q7E8";
"GATE"
$PN"1"21;
"DRN"
$PN"3"20;
"SRC"
$PN"2"6;
%"GND"
"1","(-3100,4250)","0","mstr_symbols","I120";
;
HDL_POWER"GND"
BODY_TYPE"PLUMBING"
SIZE"1B"
CDS_LIB"mstr_symbols"
VOLTAGE"0";
"A\NAC"6;
%"GND"
"1","(-3100,3675)","0","mstr_symbols","I23";
;
HDL_POWER"GND"
BODY_TYPE"PLUMBING"
CDS_LIB"mstr_symbols"
SIZE"1B"
VOLTAGE"0";
"A\NAC"7;
%"GND"
"1","(-3100,3000)","0","mstr_symbols","I26";
;
HDL_POWER"GND"
BODY_TYPE"PLUMBING"
SIZE"1B"
CDS_LIB"mstr_symbols"
VOLTAGE"0";
"A\NAC"8;
%"GND"
"1","(-3100,2350)","0","mstr_symbols","I27";
;
HDL_POWER"GND"
BODY_TYPE"PLUMBING"
SIZE"1B"
CDS_LIB"mstr_symbols"
VOLTAGE"0";
"A\NAC"9;
%"FET_N_DUAL"
"5","(-3100,2625)","0","mstr_discrete","I28";
;
CDS_SEC"1"
ROOM"PROC_SIDEBAND"
CDS_LOCATION"Q2U1"
SEC"1"
CDS_LIB"mstr_discrete"
SEC_TYPE"SMLF"
BOM_COST"PROC_SIDEBAND"
PACK_TYPE"SMLF"
MATERIAL"FET"
VALUE"NTJD4001N"
PART_NUMBER"E40049-001"
LOCATION"Q2U1";
"GATE <SIZE -1..0>"
$PN"2"21;
"SOURCE <SIZE-1..0>"
$PN"1"9;
"DRAIN <SIZE -1..0>"
$PN"6"23;
%"GND"
"1","(-3100,1675)","0","mstr_symbols","I29";
;
HDL_POWER"GND"
BODY_TYPE"PLUMBING"
SIZE"1B"
CDS_LIB"mstr_symbols"
VOLTAGE"0";
"A\NAC"10;
%"GND"
"1","(-3100,1025)","0","mstr_symbols","I30";
;
HDL_POWER"GND"
BODY_TYPE"PLUMBING"
SIZE"1B"
CDS_LIB"mstr_symbols"
VOLTAGE"0";
"A\NAC"11;
%"FET_N_DUAL"
"5","(-3100,1300)","0","mstr_discrete","I32";
;
CDS_SEC"1"
ROOM"PROC_SIDEBAND"
CDS_LOCATION"Q4B2"
SEC"1"
BOM_COST"PROC_SIDEBAND"
CDS_LIB"mstr_discrete"
SEC_TYPE"SMLF"
PACK_TYPE"SMLF"
MATERIAL"FET"
VALUE"NTJD4001N"
PART_NUMBER"E40049-001"
LOCATION"Q4B2";
"GATE <SIZE -1..0>"
$PN"2"21;
"SOURCE <SIZE-1..0>"
$PN"1"11;
"DRAIN <SIZE -1..0>"
$PN"6"25;
%"FET_N_DUAL"
"5","(-3100,700)","0","mstr_discrete","I33";
;
CDS_SEC"2"
ROOM"PROC_SIDEBAND"
CDS_LOCATION"Q4B2"
SEC"2"
BOM_COST"PROC_SIDEBAND"
CDS_LIB"mstr_discrete"
SEC_TYPE"SMLF"
PACK_TYPE"SMLF"
MATERIAL"FET"
VALUE"NTJD4001N"
PART_NUMBER"E40049-001"
LOCATION"Q4B2";
"GATE <SIZE -1..0>"
$PN"5"21;
"SOURCE <SIZE-1..0>"
$PN"4"1;
"DRAIN <SIZE -1..0>"
$PN"3"26;
%"FET_N_DUAL"
"5","(-3100,3275)","0","mstr_discrete","I51";
;
CDS_SEC"2"
ROOM"PROC_SIDEBAND"
CDS_LOCATION"Q7E3"
SEC"2"
BOM_COST"PROC_SIDEBAND"
CDS_LIB"mstr_discrete"
SEC_TYPE"SMLF"
PACK_TYPE"SMLF"
MATERIAL"FET"
VALUE"NTJD4001N"
PART_NUMBER"E40049-001"
LOCATION"Q7E3";
"GATE <SIZE -1..0>"
$PN"5"21;
"SOURCE <SIZE-1..0>"
$PN"4"8;
"DRAIN <SIZE -1..0>"
$PN"3"22;
%"FET_N_DUAL"
"5","(-3100,3950)","0","mstr_discrete","I52";
;
CDS_SEC"1"
ROOM"PROC_SIDEBAND"
CDS_LOCATION"Q7E3"
SEC"1"
BOM_COST"PROC_SIDEBAND"
CDS_LIB"mstr_discrete"
SEC_TYPE"SMLF"
PACK_TYPE"SMLF"
MATERIAL"FET"
VALUE"NTJD4001N"
PART_NUMBER"E40049-001"
LOCATION"Q7E3";
"GATE <SIZE -1..0>"
$PN"2"21;
"SOURCE <SIZE-1..0>"
$PN"1"7;
"DRAIN <SIZE -1..0>"
$PN"6"27;
%"FET_N_DUAL"
"5","(3050,4725)","0","mstr_discrete","I59";
;
CDS_SEC"2"
ROOM"HOT_EVENTS"
CDS_LOCATION"Q7E5"
SEC"2"
BOM_COST"PROC_SIDEBAND"
CDS_LIB"mstr_discrete"
SEC_TYPE"SMLF"
PACK_TYPE"SMLF"
MATERIAL"FET"
VALUE"NTJD4001N"
PART_NUMBER"E40049-001"
LOCATION"Q7E5";
"GATE <SIZE -1..0>"
$PN"5"39;
"SOURCE <SIZE-1..0>"
$PN"4"12;
"DRAIN <SIZE -1..0>"
$PN"3"40;
%"GND"
"1","(3050,4225)","0","mstr_symbols","I60";
;
HDL_POWER"GND"
ROOM"PROCHOT_MEMHOT_ISO"
BODY_TYPE"PLUMBING"
CDS_LIB"mstr_symbols"
SIZE"1B"
VOLTAGE"0.0V";
"A\NAC"12;
%"P3V3"
"1","(2475,5050)","0","mstr_symbols","I61";
;
HDL_POWER"P3V3"
ROOM"PROCHOT_MEMHOT_ISO"
BODY_TYPE"PLUMBING"
SIZE"1B"
CDS_LIB"mstr_symbols"
VOLTAGE"3.3V";
"G\NAC"13;
%"RES"
"2","(2475,4800)","2","mstr_discrete","I62";
;
ROOM"HOT_EVENTS"
CDS_LOCATION"R7E10"
$SEC"1"
CDS_SEC"1"
BOM_COST"PROC_SIDEBAND"
CDS_LIB"mstr_discrete"
MATERIAL"CHIP"
WATTAGE"1/16W"
PACK_TYPE"0402"
TOLERANCE"1%"
VALUE"4.75K"
PART_NUMBER"G21796-072"
LOCATION"R7E10";
"A"
$PN"1"13;
"B"
$PN"2"39;
%"GND"
"1","(2475,4025)","0","mstr_symbols","I63";
;
HDL_POWER"GND"
ROOM"PROCHOT_MEMHOT_ISO"
BODY_TYPE"PLUMBING"
CDS_LIB"mstr_symbols"
SIZE"1B"
VOLTAGE"0.0V";
"A\NAC"14;
%"FET_N_DUAL"
"5","(3150,3275)","0","mstr_discrete","I69";
;
CDS_SEC"2"
ROOM"HOT_EVENTS"
CDS_LOCATION"Q7E6"
SEC"2"
BOM_COST"PROC_SIDEBAND"
CDS_LIB"mstr_discrete"
SEC_TYPE"SMLF"
PACK_TYPE"SMLF"
MATERIAL"FET"
VALUE"NTJD4001N"
PART_NUMBER"E40049-001"
LOCATION"Q7E6";
"GATE <SIZE -1..0>"
$PN"5"34;
"SOURCE <SIZE-1..0>"
$PN"4"15;
"DRAIN <SIZE -1..0>"
$PN"3"35;
%"GND"
"1","(3150,2775)","0","mstr_symbols","I70";
;
HDL_POWER"GND"
ROOM"PROCHOT_MEMHOT_ISO"
BODY_TYPE"PLUMBING"
SIZE"1B"
CDS_LIB"mstr_symbols"
VOLTAGE"0.0V";
"A\NAC"15;
%"P3V3"
"1","(2550,3600)","0","mstr_symbols","I71";
;
HDL_POWER"P3V3"
ROOM"PROCHOT_MEMHOT_ISO"
BODY_TYPE"PLUMBING"
SIZE"1B"
CDS_LIB"mstr_symbols"
VOLTAGE"3.3V";
"G\NAC"16;
%"RES"
"2","(2550,3375)","2","mstr_discrete","I72";
;
ROOM"HOT_EVENTS"
CDS_LOCATION"R7E11"
$SEC"1"
CDS_SEC"1"
BOM_COST"PROC_SIDEBAND"
CDS_LIB"mstr_discrete"
MATERIAL"CHIP"
WATTAGE"1/16W"
PACK_TYPE"0402"
TOLERANCE"1%"
VALUE"4.75K"
PART_NUMBER"G21796-072"
LOCATION"R7E11";
"A"
$PN"1"16;
"B"
$PN"2"34;
%"GND"
"1","(2550,2575)","0","mstr_symbols","I73";
;
HDL_POWER"GND"
ROOM"PROCHOT_MEMHOT_ISO"
BODY_TYPE"PLUMBING"
SIZE"1B"
CDS_LIB"mstr_symbols"
VOLTAGE"0.0V";
"A\NAC"17;
%"CAP_A"
"1","(700,4775)","0","dev_discrete","I92";
;
SEC"1"
SEC_TYPE"0402V"
CDS_SEC"1"
CDS_LIB"dev_discrete"
BOM_COST"PROC_SIDEBAND"
CDS_LOCATION"C7E3"
ROOM"PROC_SIDEBAND"
MATERIAL"X7R"
VOLTAGE"16V"
PACK_TYPE"0402V"
TOLERANCE"10%"
VALUE"0.1UF"
PART_NUMBER"A36096-030"
LOCATION"C7E3";
"B"
$PN"2"18;
"A"
$PN"1"19;
%"GND"
"1","(700,4525)","0","mstr_symbols","I94";
;
HDL_POWER"GND"
BODY_TYPE"PLUMBING"
SIZE"1B"
CDS_LIB"mstr_symbols"
VOLTAGE"0.0V";
"A\NAC"18;
%"P3V3_STBY"
"1","(700,5000)","0","mstr_symbols","I98";
;
HDL_POWER"P3V3_STBY"
BODY_TYPE"PLUMBING"
SIZE"1B"
CDS_LIB"mstr_symbols"
VOLTAGE"3.3V";
"G\NAC"19;
END.
